(kicad_pcb
	(version 20260206)
	(generator "pcbnew")
	(generator_version "10.0")
	(general
		(thickness 1.6)
		(legacy_teardrops no)
	)
	(paper "A4")
	(title_block
		(title "01162023_DA0F0TEBIF0_F0T_Expander_BD_F_brd_V02_OCP.brd")
		(comment 1 "Grand Teton / footprints 5842-5849 of 9728")
	)
	(layers
		(0 "F.Cu" signal "TOP")
		(4 "In1.Cu" signal "GND")
		(6 "In2.Cu" signal "VCC")
		(8 "In3.Cu" signal "VCC1")
		(10 "In4.Cu" signal "GND1")
		(12 "In5.Cu" signal "IN1")
		(14 "In6.Cu" signal "GND2")
		(16 "In7.Cu" signal "IN2")
		(18 "In8.Cu" signal "GND3")
		(20 "In9.Cu" signal "IN3")
		(22 "In10.Cu" signal "GND4")
		(24 "In11.Cu" signal "IN4")
		(26 "In12.Cu" signal "GND5")
		(28 "In13.Cu" signal "IN5")
		(30 "In14.Cu" signal "GND6")
		(32 "In15.Cu" signal "IN6")
		(34 "In16.Cu" signal "GND7")
		(2 "B.Cu" signal "BOTTOM")
		(9 "F.Adhes" user "F.Adhesive")
		(11 "B.Adhes" user "B.Adhesive")
		(13 "F.Paste" user "Package Geometry/Pastemask Top")
		(15 "B.Paste" user "Package Geometry/Pastemask Bottom")
		(5 "F.SilkS" user "Ref Des/Silkscreen Top")
		(7 "B.SilkS" user "Ref Des/Silkscreen Bottom")
		(1 "F.Mask" user "Board Geometry/Soldermask Top")
		(3 "B.Mask" user "Board Geometry/Soldermask Bottom")
		(17 "Dwgs.User" user "User.Drawings")
		(19 "Cmts.User" user "User.Comments")
		(21 "Eco1.User" user "User.Eco1")
		(23 "Eco2.User" user "User.Eco2")
		(25 "Edge.Cuts" user "Board Geometry/Outline")
		(27 "Margin" user)
		(31 "F.CrtYd" user "Package Geometry/Place Bound Top")
		(29 "B.CrtYd" user "Package Geometry/Place Bound Bottom")
		(35 "F.Fab" user "Ref Des/Assembly Top")
		(33 "B.Fab" user "Ref Des/Assembly Bottom")
	)
	(footprint ""
		(layer "F.Cu")
		(at 262.57377 -27.006296 -90)
		(property "Reference" "PC946"
			(at 0 0 270)
			(layer "F.SilkS")
			(hide yes)
			(effects
				(font
					(size 1.27 1.27)
				)
			)
		)
		(property "Value" ""
			(at 0 0 270)
			(layer "F.Fab")
			(effects
				(font
					(size 1.27 1.27)
				)
			)
		)
		(duplicate_pad_numbers_are_jumpers no)
		(fp_line
			(start -0.7874 0.4064)
			(end -0.7874 -0.4064)
			(stroke
				(width 0.1524)
				(type default)
			)
			(layer "F.SilkS")
		)
		(fp_line
			(start 0.7874 0.4064)
			(end -0.7874 0.4064)
			(stroke
				(width 0.1524)
				(type default)
			)
			(layer "F.SilkS")
		)
		(fp_line
			(start -0.7874 -0.4064)
			(end 0.7874 -0.4064)
			(stroke
				(width 0.1524)
				(type default)
			)
			(layer "F.SilkS")
		)
		(fp_line
			(start 0.7874 -0.4064)
			(end 0.7874 0.4064)
			(stroke
				(width 0.1524)
				(type default)
			)
			(layer "F.SilkS")
		)
		(fp_line
			(start -0.67945 0.3048)
			(end -0.67945 -0.305054)
			(stroke
				(width 0.1)
				(type default)
			)
			(layer "F.Fab")
		)
		(fp_line
			(start -0.12065 0.3048)
			(end -0.67945 0.3048)
			(stroke
				(width 0.1)
				(type default)
			)
			(layer "F.Fab")
		)
		(fp_line
			(start 0.120396 0.3048)
			(end 0.120396 0.2794)
			(stroke
				(width 0.1)
				(type default)
			)
			(layer "F.Fab")
		)
		(fp_line
			(start 0.67945 0.3048)
			(end 0.120396 0.3048)
			(stroke
				(width 0.1)
				(type default)
			)
			(layer "F.Fab")
		)
		(fp_line
			(start -0.12065 0.2794)
			(end -0.12065 0.3048)
			(stroke
				(width 0.1)
				(type default)
			)
			(layer "F.Fab")
		)
		(fp_line
			(start 0.120396 0.2794)
			(end -0.12065 0.2794)
			(stroke
				(width 0.1)
				(type default)
			)
			(layer "F.Fab")
		)
		(fp_line
			(start -0.12065 -0.2794)
			(end 0.12065 -0.2794)
			(stroke
				(width 0.1)
				(type default)
			)
			(layer "F.Fab")
		)
		(fp_line
			(start 0.12065 -0.2794)
			(end 0.12065 -0.3048)
			(stroke
				(width 0.1)
				(type default)
			)
			(layer "F.Fab")
		)
		(fp_line
			(start 0.12065 -0.3048)
			(end 0.67945 -0.3048)
			(stroke
				(width 0.1)
				(type default)
			)
			(layer "F.Fab")
		)
		(fp_line
			(start 0.67945 -0.3048)
			(end 0.67945 0.3048)
			(stroke
				(width 0.1)
				(type default)
			)
			(layer "F.Fab")
		)
		(fp_line
			(start -0.67945 -0.305054)
			(end -0.12065 -0.305054)
			(stroke
				(width 0.1)
				(type default)
			)
			(layer "F.Fab")
		)
		(fp_line
			(start -0.12065 -0.305054)
			(end -0.12065 -0.2794)
			(stroke
				(width 0.1)
				(type default)
			)
			(layer "F.Fab")
		)
		(pad "1" smd circle
			(at -0.40005 0 270)
			(size 0 0)
			(layers "F.Cu" "F.Mask" "F.Paste")
			(net "P3V3_SSD9_CO_MODE")
		)
		(pad "2" smd circle
			(at 0.40005 0 270)
			(size 0 0)
			(layers "F.Cu" "F.Mask" "F.Paste")
			(net "GND")
		)
	)
	(footprint ""
		(layer "F.Cu")
		(at 289.634422 -343.952322 90)
		(property "Reference" "C594"
			(at 0 0 90)
			(layer "F.SilkS")
			(hide yes)
			(effects
				(font
					(size 1.27 1.27)
				)
			)
		)
		(property "Value" ""
			(at 0 0 90)
			(layer "F.Fab")
			(effects
				(font
					(size 1.27 1.27)
				)
			)
		)
		(duplicate_pad_numbers_are_jumpers no)
		(fp_line
			(start 0.299974 -0.150114)
			(end 0.299974 0.150114)
			(stroke
				(width 0.1)
				(type default)
			)
			(layer "F.Fab")
		)
		(fp_line
			(start -0.299974 -0.150114)
			(end 0.299974 -0.150114)
			(stroke
				(width 0.1)
				(type default)
			)
			(layer "F.Fab")
		)
		(fp_line
			(start 0.299974 0.150114)
			(end -0.299974 0.150114)
			(stroke
				(width 0.1)
				(type default)
			)
			(layer "F.Fab")
		)
		(fp_line
			(start -0.299974 0.150114)
			(end -0.299974 -0.150114)
			(stroke
				(width 0.1)
				(type default)
			)
			(layer "F.Fab")
		)
		(pad "1" smd rect
			(at -0.2667 0 90)
			(size 0.3048 0.381)
			(layers "F.Cu" "F.Mask" "F.Paste")
			(net "P5E_PEX2_STN7_TX_DN<122>")
		)
		(pad "2" smd rect
			(at 0.2667 0 90)
			(size 0.3048 0.381)
			(layers "F.Cu" "F.Mask" "F.Paste")
			(net "P5E_PEX2_STN7_TX_C_DN<122>")
		)
	)
	(footprint ""
		(layer "F.Cu")
		(at 152.738328 -109.20984)
		(property "Reference" "C265"
			(at 0 0 0)
			(layer "F.SilkS")
			(hide yes)
			(effects
				(font
					(size 1.27 1.27)
				)
			)
		)
		(property "Value" ""
			(at 0 0 0)
			(layer "F.Fab")
			(effects
				(font
					(size 1.27 1.27)
				)
			)
		)
		(duplicate_pad_numbers_are_jumpers no)
		(fp_line
			(start -0.299974 -0.150114)
			(end 0.299974 -0.150114)
			(stroke
				(width 0.1)
				(type default)
			)
			(layer "F.Fab")
		)
		(fp_line
			(start -0.299974 0.150114)
			(end -0.299974 -0.150114)
			(stroke
				(width 0.1)
				(type default)
			)
			(layer "F.Fab")
		)
		(fp_line
			(start 0.299974 -0.150114)
			(end 0.299974 0.150114)
			(stroke
				(width 0.1)
				(type default)
			)
			(layer "F.Fab")
		)
		(fp_line
			(start 0.299974 0.150114)
			(end -0.299974 0.150114)
			(stroke
				(width 0.1)
				(type default)
			)
			(layer "F.Fab")
		)
		(pad "1" smd rect
			(at -0.2667 0)
			(size 0.3048 0.381)
			(layers "F.Cu" "F.Mask" "F.Paste")
			(net "P5E_PEX1_STN1_TX_DP<21>")
		)
		(pad "2" smd rect
			(at 0.2667 0)
			(size 0.3048 0.381)
			(layers "F.Cu" "F.Mask" "F.Paste")
			(net "P5E_PEX1_STN1_TX_C_DP<21>")
		)
	)
	(footprint ""
		(layer "F.Cu")
		(at 287.439862 -343.952322 90)
		(property "Reference" "C2358"
			(at 0 0 90)
			(layer "F.SilkS")
			(hide yes)
			(effects
				(font
					(size 1.27 1.27)
				)
			)
		)
		(property "Value" ""
			(at 0 0 90)
			(layer "F.Fab")
			(effects
				(font
					(size 1.27 1.27)
				)
			)
		)
		(duplicate_pad_numbers_are_jumpers no)
		(fp_line
			(start 0.299974 -0.150114)
			(end 0.299974 0.150114)
			(stroke
				(width 0.1)
				(type default)
			)
			(layer "F.Fab")
		)
		(fp_line
			(start -0.299974 -0.150114)
			(end 0.299974 -0.150114)
			(stroke
				(width 0.1)
				(type default)
			)
			(layer "F.Fab")
		)
		(fp_line
			(start 0.299974 0.150114)
			(end -0.299974 0.150114)
			(stroke
				(width 0.1)
				(type default)
			)
			(layer "F.Fab")
		)
		(fp_line
			(start -0.299974 0.150114)
			(end -0.299974 -0.150114)
			(stroke
				(width 0.1)
				(type default)
			)
			(layer "F.Fab")
		)
		(pad "1" smd rect
			(at -0.2667 0 90)
			(size 0.3048 0.381)
			(layers "F.Cu" "F.Mask" "F.Paste")
			(net "P5E_PEX2_STN4_TX_DN<71>")
		)
		(pad "2" smd rect
			(at 0.2667 0 90)
			(size 0.3048 0.381)
			(layers "F.Cu" "F.Mask" "F.Paste")
			(net "P5E_PEX2_STN4_TX_C_DN<71>")
		)
	)
	(footprint ""
		(layer "F.Cu")
		(at 346.075 -234.061 -90)
		(property "Reference" "R3554"
			(at 0 0 270)
			(layer "F.SilkS")
			(hide yes)
			(effects
				(font
					(size 1.27 1.27)
				)
			)
		)
		(property "Value" ""
			(at 0 0 270)
			(layer "F.Fab")
			(effects
				(font
					(size 1.27 1.27)
				)
			)
		)
		(duplicate_pad_numbers_are_jumpers no)
		(fp_line
			(start -0.7874 0.4064)
			(end -0.7874 -0.4064)
			(stroke
				(width 0.1524)
				(type default)
			)
			(layer "F.SilkS")
		)
		(fp_line
			(start 0.7874 0.4064)
			(end -0.7874 0.4064)
			(stroke
				(width 0.1524)
				(type default)
			)
			(layer "F.SilkS")
		)
		(fp_line
			(start -0.7874 -0.4064)
			(end 0.7874 -0.4064)
			(stroke
				(width 0.1524)
				(type default)
			)
			(layer "F.SilkS")
		)
		(fp_line
			(start 0.7874 -0.4064)
			(end 0.7874 0.4064)
			(stroke
				(width 0.1524)
				(type default)
			)
			(layer "F.SilkS")
		)
		(fp_line
			(start -0.67945 0.3048)
			(end -0.67945 -0.305054)
			(stroke
				(width 0.1)
				(type default)
			)
			(layer "F.Fab")
		)
		(fp_line
			(start -0.12065 0.3048)
			(end -0.67945 0.3048)
			(stroke
				(width 0.1)
				(type default)
			)
			(layer "F.Fab")
		)
		(fp_line
			(start 0.120396 0.3048)
			(end 0.120396 0.2794)
			(stroke
				(width 0.1)
				(type default)
			)
			(layer "F.Fab")
		)
		(fp_line
			(start 0.67945 0.3048)
			(end 0.120396 0.3048)
			(stroke
				(width 0.1)
				(type default)
			)
			(layer "F.Fab")
		)
		(fp_line
			(start -0.12065 0.2794)
			(end -0.12065 0.3048)
			(stroke
				(width 0.1)
				(type default)
			)
			(layer "F.Fab")
		)
		(fp_line
			(start 0.120396 0.2794)
			(end -0.12065 0.2794)
			(stroke
				(width 0.1)
				(type default)
			)
			(layer "F.Fab")
		)
		(fp_line
			(start -0.12065 -0.2794)
			(end 0.12065 -0.2794)
			(stroke
				(width 0.1)
				(type default)
			)
			(layer "F.Fab")
		)
		(fp_line
			(start 0.12065 -0.2794)
			(end 0.12065 -0.3048)
			(stroke
				(width 0.1)
				(type default)
			)
			(layer "F.Fab")
		)
		(fp_line
			(start 0.12065 -0.3048)
			(end 0.67945 -0.3048)
			(stroke
				(width 0.1)
				(type default)
			)
			(layer "F.Fab")
		)
		(fp_line
			(start 0.67945 -0.3048)
			(end 0.67945 0.3048)
			(stroke
				(width 0.1)
				(type default)
			)
			(layer "F.Fab")
		)
		(fp_line
			(start -0.67945 -0.305054)
			(end -0.12065 -0.305054)
			(stroke
				(width 0.1)
				(type default)
			)
			(layer "F.Fab")
		)
		(fp_line
			(start -0.12065 -0.305054)
			(end -0.12065 -0.2794)
			(stroke
				(width 0.1)
				(type default)
			)
			(layer "F.Fab")
		)
		(pad "1" smd circle
			(at -0.40005 0 270)
			(size 0 0)
			(layers "F.Cu" "F.Mask" "F.Paste")
			(net "RST_SSD4_PERST_R_N")
		)
		(pad "2" smd circle
			(at 0.40005 0 270)
			(size 0 0)
			(layers "F.Cu" "F.Mask" "F.Paste")
			(net "RST_SSD4_PERST_N")
		)
	)
	(footprint ""
		(layer "F.Cu")
		(at 102.383336 -49.94148)
		(property "Reference" "R5895"
			(at 0 0 0)
			(layer "F.SilkS")
			(hide yes)
			(effects
				(font
					(size 1.27 1.27)
				)
			)
		)
		(property "Value" ""
			(at 0 0 0)
			(layer "F.Fab")
			(effects
				(font
					(size 1.27 1.27)
				)
			)
		)
		(duplicate_pad_numbers_are_jumpers no)
		(fp_line
			(start -0.7874 -0.4064)
			(end 0.7874 -0.4064)
			(stroke
				(width 0.1524)
				(type default)
			)
			(layer "F.SilkS")
		)
		(fp_line
			(start -0.7874 0.4064)
			(end -0.7874 -0.4064)
			(stroke
				(width 0.1524)
				(type default)
			)
			(layer "F.SilkS")
		)
		(fp_line
			(start 0.7874 -0.4064)
			(end 0.7874 0.4064)
			(stroke
				(width 0.1524)
				(type default)
			)
			(layer "F.SilkS")
		)
		(fp_line
			(start 0.7874 0.4064)
			(end -0.7874 0.4064)
			(stroke
				(width 0.1524)
				(type default)
			)
			(layer "F.SilkS")
		)
		(fp_line
			(start -0.67945 -0.305054)
			(end -0.12065 -0.305054)
			(stroke
				(width 0.1)
				(type default)
			)
			(layer "F.Fab")
		)
		(fp_line
			(start -0.67945 0.3048)
			(end -0.67945 -0.305054)
			(stroke
				(width 0.1)
				(type default)
			)
			(layer "F.Fab")
		)
		(fp_line
			(start -0.12065 -0.305054)
			(end -0.12065 -0.2794)
			(stroke
				(width 0.1)
				(type default)
			)
			(layer "F.Fab")
		)
		(fp_line
			(start -0.12065 -0.2794)
			(end 0.12065 -0.2794)
			(stroke
				(width 0.1)
				(type default)
			)
			(layer "F.Fab")
		)
		(fp_line
			(start -0.12065 0.2794)
			(end -0.12065 0.3048)
			(stroke
				(width 0.1)
				(type default)
			)
			(layer "F.Fab")
		)
		(fp_line
			(start -0.12065 0.3048)
			(end -0.67945 0.3048)
			(stroke
				(width 0.1)
				(type default)
			)
			(layer "F.Fab")
		)
		(fp_line
			(start 0.120396 0.2794)
			(end -0.12065 0.2794)
			(stroke
				(width 0.1)
				(type default)
			)
			(layer "F.Fab")
		)
		(fp_line
			(start 0.120396 0.3048)
			(end 0.120396 0.2794)
			(stroke
				(width 0.1)
				(type default)
			)
			(layer "F.Fab")
		)
		(fp_line
			(start 0.12065 -0.3048)
			(end 0.67945 -0.3048)
			(stroke
				(width 0.1)
				(type default)
			)
			(layer "F.Fab")
		)
		(fp_line
			(start 0.12065 -0.2794)
			(end 0.12065 -0.3048)
			(stroke
				(width 0.1)
				(type default)
			)
			(layer "F.Fab")
		)
		(fp_line
			(start 0.67945 -0.3048)
			(end 0.67945 0.3048)
			(stroke
				(width 0.1)
				(type default)
			)
			(layer "F.Fab")
		)
		(fp_line
			(start 0.67945 0.3048)
			(end 0.120396 0.3048)
			(stroke
				(width 0.1)
				(type default)
			)
			(layer "F.Fab")
		)
		(pad "1" smd circle
			(at -0.40005 0)
			(size 0 0)
			(layers "F.Cu" "F.Mask" "F.Paste")
			(net "SSD3_ADC_A0")
		)
		(pad "2" smd circle
			(at 0.40005 0)
			(size 0 0)
			(layers "F.Cu" "F.Mask" "F.Paste")
			(net "SMB_SSD3_ADC_SCL")
		)
	)
	(footprint ""
		(layer "F.Cu")
		(at 161.896298 -47.20082 90)
		(property "Reference" "C313"
			(at 0 0 90)
			(layer "F.SilkS")
			(hide yes)
			(effects
				(font
					(size 1.27 1.27)
				)
			)
		)
		(property "Value" ""
			(at 0 0 90)
			(layer "F.Fab")
			(effects
				(font
					(size 1.27 1.27)
				)
			)
		)
		(duplicate_pad_numbers_are_jumpers no)
		(fp_line
			(start 0.7874 -0.4064)
			(end 0.7874 0.4064)
			(stroke
				(width 0.1524)
				(type default)
			)
			(layer "F.SilkS")
		)
		(fp_line
			(start -0.7874 -0.4064)
			(end 0.7874 -0.4064)
			(stroke
				(width 0.1524)
				(type default)
			)
			(layer "F.SilkS")
		)
		(fp_line
			(start 0.7874 0.4064)
			(end -0.7874 0.4064)
			(stroke
				(width 0.1524)
				(type default)
			)
			(layer "F.SilkS")
		)
		(fp_line
			(start -0.7874 0.4064)
			(end -0.7874 -0.4064)
			(stroke
				(width 0.1524)
				(type default)
			)
			(layer "F.SilkS")
		)
		(fp_line
			(start -0.12065 -0.305054)
			(end -0.12065 -0.2794)
			(stroke
				(width 0.1)
				(type default)
			)
			(layer "F.Fab")
		)
		(fp_line
			(start -0.67945 -0.305054)
			(end -0.12065 -0.305054)
			(stroke
				(width 0.1)
				(type default)
			)
			(layer "F.Fab")
		)
		(fp_line
			(start 0.67945 -0.3048)
			(end 0.67945 0.3048)
			(stroke
				(width 0.1)
				(type default)
			)
			(layer "F.Fab")
		)
		(fp_line
			(start 0.12065 -0.3048)
			(end 0.67945 -0.3048)
			(stroke
				(width 0.1)
				(type default)
			)
			(layer "F.Fab")
		)
		(fp_line
			(start 0.12065 -0.2794)
			(end 0.12065 -0.3048)
			(stroke
				(width 0.1)
				(type default)
			)
			(layer "F.Fab")
		)
		(fp_line
			(start -0.12065 -0.2794)
			(end 0.12065 -0.2794)
			(stroke
				(width 0.1)
				(type default)
			)
			(layer "F.Fab")
		)
		(fp_line
			(start 0.120396 0.2794)
			(end -0.12065 0.2794)
			(stroke
				(width 0.1)
				(type default)
			)
			(layer "F.Fab")
		)
		(fp_line
			(start -0.12065 0.2794)
			(end -0.12065 0.3048)
			(stroke
				(width 0.1)
				(type default)
			)
			(layer "F.Fab")
		)
		(fp_line
			(start 0.67945 0.3048)
			(end 0.120396 0.3048)
			(stroke
				(width 0.1)
				(type default)
			)
			(layer "F.Fab")
		)
		(fp_line
			(start 0.120396 0.3048)
			(end 0.120396 0.2794)
			(stroke
				(width 0.1)
				(type default)
			)
			(layer "F.Fab")
		)
		(fp_line
			(start -0.12065 0.3048)
			(end -0.67945 0.3048)
			(stroke
				(width 0.1)
				(type default)
			)
			(layer "F.Fab")
		)
		(fp_line
			(start -0.67945 0.3048)
			(end -0.67945 -0.305054)
			(stroke
				(width 0.1)
				(type default)
			)
			(layer "F.Fab")
		)
		(pad "1" smd circle
			(at -0.40005 0 90)
			(size 0 0)
			(layers "F.Cu" "F.Mask" "F.Paste")
			(net "P12V_SSD5_R")
		)
		(pad "2" smd circle
			(at 0.40005 0 90)
			(size 0 0)
			(layers "F.Cu" "F.Mask" "F.Paste")
			(net "GND")
		)
	)
	(footprint ""
		(layer "F.Cu")
		(at 359.85831 -255.210564 180)
		(property "Reference" "C835"
			(at 0 0 180)
			(layer "F.SilkS")
			(hide yes)
			(effects
				(font
					(size 1.27 1.27)
				)
			)
		)
		(property "Value" ""
			(at 0 0 180)
			(layer "F.Fab")
			(effects
				(font
					(size 1.27 1.27)
				)
			)
		)
		(duplicate_pad_numbers_are_jumpers no)
		(fp_line
			(start 0.7874 0.4064)
			(end -0.7874 0.4064)
			(stroke
				(width 0.1524)
				(type default)
			)
			(layer "F.SilkS")
		)
		(fp_line
			(start 0.7874 -0.4064)
			(end 0.7874 0.4064)
			(stroke
				(width 0.1524)
				(type default)
			)
			(layer "F.SilkS")
		)
		(fp_line
			(start -0.7874 0.4064)
			(end -0.7874 -0.4064)
			(stroke
				(width 0.1524)
				(type default)
			)
			(layer "F.SilkS")
		)
		(fp_line
			(start -0.7874 -0.4064)
			(end 0.7874 -0.4064)
			(stroke
				(width 0.1524)
				(type default)
			)
			(layer "F.SilkS")
		)
		(fp_line
			(start 0.67945 0.3048)
			(end 0.120396 0.3048)
			(stroke
				(width 0.1)
				(type default)
			)
			(layer "F.Fab")
		)
		(fp_line
			(start 0.67945 -0.3048)
			(end 0.67945 0.3048)
			(stroke
				(width 0.1)
				(type default)
			)
			(layer "F.Fab")
		)
		(fp_line
			(start 0.12065 -0.2794)
			(end 0.12065 -0.3048)
			(stroke
				(width 0.1)
				(type default)
			)
			(layer "F.Fab")
		)
		(fp_line
			(start 0.12065 -0.3048)
			(end 0.67945 -0.3048)
			(stroke
				(width 0.1)
				(type default)
			)
			(layer "F.Fab")
		)
		(fp_line
			(start 0.120396 0.3048)
			(end 0.120396 0.2794)
			(stroke
				(width 0.1)
				(type default)
			)
			(layer "F.Fab")
		)
		(fp_line
			(start 0.120396 0.2794)
			(end -0.12065 0.2794)
			(stroke
				(width 0.1)
				(type default)
			)
			(layer "F.Fab")
		)
		(fp_line
			(start -0.12065 0.3048)
			(end -0.67945 0.3048)
			(stroke
				(width 0.1)
				(type default)
			)
			(layer "F.Fab")
		)
		(fp_line
			(start -0.12065 0.2794)
			(end -0.12065 0.3048)
			(stroke
				(width 0.1)
				(type default)
			)
			(layer "F.Fab")
		)
		(fp_line
			(start -0.12065 -0.2794)
			(end 0.12065 -0.2794)
			(stroke
				(width 0.1)
				(type default)
			)
			(layer "F.Fab")
		)
		(fp_line
			(start -0.12065 -0.305054)
			(end -0.12065 -0.2794)
			(stroke
				(width 0.1)
				(type default)
			)
			(layer "F.Fab")
		)
		(fp_line
			(start -0.67945 0.3048)
			(end -0.67945 -0.305054)
			(stroke
				(width 0.1)
				(type default)
			)
			(layer "F.Fab")
		)
		(fp_line
			(start -0.67945 -0.305054)
			(end -0.12065 -0.305054)
			(stroke
				(width 0.1)
				(type default)
			)
			(layer "F.Fab")
		)
		(pad "1" smd circle
			(at -0.40005 0 180)
			(size 0 0)
			(layers "F.Cu" "F.Mask" "F.Paste")
			(net "GND")
		)
		(pad "2" smd circle
			(at 0.40005 0 180)
			(size 0 0)
			(layers "F.Cu" "F.Mask" "F.Paste")
			(net "FM_P0V8_PEX2_EN_R")
		)
	)
)
